FILE_TYPE = CONNECTIVITY;
{Allegro Design Entry HDL 17.2-2016 S081 (4005846) 1/11/2022}
"PAGE_NUMBER" = 128;
0"NC";
END.
